(kicad_pcb
	(version 20260206)
	(generator "pcbnew")
	(generator_version "10.0")
	(general
		(thickness 1.6)
		(legacy_teardrops no)
	)
	(paper "A4")
	(title_block
		(title "4HDD Backplane_Layout.brd")
		(comment 1 "Tioga Pass / footprint 56 of 97 (SATA4), pads 1-32 of 32")
	)
	(layers
		(0 "F.Cu" signal "TOP")
		(4 "In1.Cu" signal "L2GND")
		(6 "In2.Cu" signal "L3")
		(8 "In3.Cu" signal "L4")
		(10 "In4.Cu" signal "L5GND")
		(2 "B.Cu" signal "BOTTOM")
		(9 "F.Adhes" user "F.Adhesive")
		(11 "B.Adhes" user "B.Adhesive")
		(13 "F.Paste" user "Package Geometry/Pastemask Top")
		(15 "B.Paste" user "Package Geometry/Pastemask Bottom")
		(5 "F.SilkS" user "Ref Des/Silkscreen Top")
		(7 "B.SilkS" user "Ref Des/Silkscreen Bottom")
		(1 "F.Mask" user "Board Geometry/Soldermask Top")
		(3 "B.Mask" user "Board Geometry/Soldermask Bottom")
		(17 "Dwgs.User" user "User.Drawings")
		(19 "Cmts.User" user "User.Comments")
		(21 "Eco1.User" user "User.Eco1")
		(23 "Eco2.User" user "User.Eco2")
		(25 "Edge.Cuts" user "Board Geometry/Outline")
		(27 "Margin" user)
		(31 "F.CrtYd" user "Package Geometry/Place Bound Top")
		(29 "B.CrtYd" user "Package Geometry/Place Bound Bottom")
		(35 "F.Fab" user "Ref Des/Assembly Top")
		(33 "B.Fab" user "Ref Des/Assembly Bottom")
	)
	(footprint ""
		(layer "F.Cu")
		(at 33.219898 -3.819906 180)
		(property "Reference" "SATA4"
			(at 0 0 180)
			(layer "F.SilkS")
			(hide yes)
			(effects
				(font
					(size 1.27 1.27)
				)
			)
		)
		(property "Value" "FCI-CONN29-2R-GP-U"
			(at -35.2552 -14.1859 180)
			(unlocked yes)
			(layer "F.Fab")
			(hide yes)
			(effects
				(font
					(size 1.016 1.016)
					(thickness 0.1524)
				)
			)
		)
		(property "Device Type" "PREFIT-29P-458055-UH395"
			(at -35.2552 -15.7099 180)
			(unlocked yes)
			(layer "F.Fab")
			(hide yes)
			(effects
				(font
					(size 1.016 1.016)
					(thickness 0.1524)
				)
			)
		)
		(duplicate_pad_numbers_are_jumpers no)
		(pad "" np_thru_hole circle
			(at -23.95474 0 180)
			(size 0.254 0.254)
			(drill 1.3462)
			(layers "*.Cu" "*.Mask")
			(clearance 0.9017)
			(thermal_gap 0.9017)
		)
		(pad "30" thru_hole circle
			(at -26.07945 0 180)
			(size 2.3622 2.3622)
			(drill 1.949958)
			(layers "*.Cu" "*.Mask")
			(remove_unused_layers no)
			(net "Net_53")
			(clearance 0.1524)
			(thermal_gap 0.1524)
		)
		(pad "31" thru_hole circle
			(at 15.91945 0 180)
			(size 2.3622 2.3622)
			(drill 1.949958)
			(layers "*.Cu" "*.Mask")
			(remove_unused_layers no)
			(net "Net_44")
			(clearance 0.1524)
			(thermal_gap 0.1524)
		)
		(pad "P1" thru_hole circle
			(at -3.175 -1.27 180)
			(size 0.8636 0.8636)
			(drill 0.499872)
			(layers "*.Cu" "*.Mask")
			(remove_unused_layers no)
			(net "Net_49")
			(clearance 0.1778)
			(thermal_gap 0.1778)
		)
		(pad "P2" thru_hole circle
			(at -4.445 -1.27 180)
			(size 0.8636 0.8636)
			(drill 0.499872)
			(layers "*.Cu" "*.Mask")
			(remove_unused_layers no)
			(net "Net_51")
			(clearance 0.1778)
			(thermal_gap 0.1778)
		)
		(pad "P3" thru_hole circle
			(at -5.715 -1.27 180)
			(size 0.8636 0.8636)
			(drill 0.499872)
			(layers "*.Cu" "*.Mask")
			(remove_unused_layers no)
			(net "Net_50")
			(clearance 0.1778)
			(thermal_gap 0.1778)
		)
		(pad "P4" thru_hole circle
			(at -6.985 -1.27 180)
			(size 0.8636 0.8636)
			(drill 0.499872)
			(layers "*.Cu" "*.Mask")
			(remove_unused_layers no)
			(net "GND")
			(clearance 0.1778)
			(thermal_gap 0.1778)
		)
		(pad "P5" thru_hole circle
			(at -8.255 -1.27 180)
			(size 0.8636 0.8636)
			(drill 0.499872)
			(layers "*.Cu" "*.Mask")
			(remove_unused_layers no)
			(net "GND")
			(clearance 0.1778)
			(thermal_gap 0.1778)
		)
		(pad "P6" thru_hole circle
			(at -9.525 -1.27 180)
			(size 0.8636 0.8636)
			(drill 0.499872)
			(layers "*.Cu" "*.Mask")
			(remove_unused_layers no)
			(net "GND")
			(clearance 0.1778)
			(thermal_gap 0.1778)
		)
		(pad "P7" thru_hole circle
			(at -10.795 -1.27 180)
			(size 0.8636 0.8636)
			(drill 0.499872)
			(layers "*.Cu" "*.Mask")
			(remove_unused_layers no)
			(net "5V_PRE_3")
			(clearance 0.1778)
			(thermal_gap 0.1778)
		)
		(pad "P8" thru_hole circle
			(at -12.065 -1.27 180)
			(size 0.8636 0.8636)
			(drill 0.499872)
			(layers "*.Cu" "*.Mask")
			(remove_unused_layers no)
			(net "P5V_SW_L")
			(clearance 0.1778)
			(thermal_gap 0.1778)
		)
		(pad "P9" thru_hole circle
			(at -13.335 -1.27 180)
			(size 0.8636 0.8636)
			(drill 0.499872)
			(layers "*.Cu" "*.Mask")
			(remove_unused_layers no)
			(net "P5V_SW_L")
			(clearance 0.1778)
			(thermal_gap 0.1778)
		)
		(pad "P10" thru_hole circle
			(at -14.605 -1.27 180)
			(size 0.8636 0.8636)
			(drill 0.499872)
			(layers "*.Cu" "*.Mask")
			(remove_unused_layers no)
			(net "HBA_PRSNT3_N")
			(clearance 0.1778)
			(thermal_gap 0.1778)
		)
		(pad "P11" thru_hole circle
			(at -15.875 -1.27 180)
			(size 0.8636 0.8636)
			(drill 0.499872)
			(layers "*.Cu" "*.Mask")
			(remove_unused_layers no)
			(net "HDD_ACT_LED3")
			(clearance 0.1778)
			(thermal_gap 0.1778)
		)
		(pad "P12" thru_hole circle
			(at -17.145 -1.27 180)
			(size 0.8636 0.8636)
			(drill 0.499872)
			(layers "*.Cu" "*.Mask")
			(remove_unused_layers no)
			(net "GND")
			(clearance 0.1778)
			(thermal_gap 0.1778)
		)
		(pad "P13" thru_hole circle
			(at -18.415 -1.27 180)
			(size 0.8636 0.8636)
			(drill 0.499872)
			(layers "*.Cu" "*.Mask")
			(remove_unused_layers no)
			(net "12V_PRE_3")
			(clearance 0.1778)
			(thermal_gap 0.1778)
		)
		(pad "P14" thru_hole circle
			(at -19.685 -1.27 180)
			(size 0.8636 0.8636)
			(drill 0.499872)
			(layers "*.Cu" "*.Mask")
			(remove_unused_layers no)
			(net "P12V_SW_L")
			(clearance 0.1778)
			(thermal_gap 0.1778)
		)
		(pad "P15" thru_hole circle
			(at -20.955 -1.27 180)
			(size 0.8636 0.8636)
			(drill 0.499872)
			(layers "*.Cu" "*.Mask")
			(remove_unused_layers no)
			(net "P12V_SW_L")
			(clearance 0.1778)
			(thermal_gap 0.1778)
		)
		(pad "S1" thru_hole circle
			(at 10.795 -1.27 180)
			(size 0.8636 0.8636)
			(drill 0.499872)
			(layers "*.Cu" "*.Mask")
			(remove_unused_layers no)
			(net "GND")
			(clearance 0.1778)
			(thermal_gap 0.1778)
		)
		(pad "S2" thru_hole circle
			(at 9.525 -1.27 180)
			(size 0.8636 0.8636)
			(drill 0.499872)
			(layers "*.Cu" "*.Mask")
			(remove_unused_layers no)
			(net "HBA_MB_TX_P3")
			(clearance 0.1778)
			(thermal_gap 0.1778)
		)
		(pad "S3" thru_hole circle
			(at 8.255 -1.27 180)
			(size 0.8636 0.8636)
			(drill 0.499872)
			(layers "*.Cu" "*.Mask")
			(remove_unused_layers no)
			(net "HBA_MB_TX_N3")
			(clearance 0.1778)
			(thermal_gap 0.1778)
		)
		(pad "S4" thru_hole circle
			(at 6.985 -1.27 180)
			(size 0.8636 0.8636)
			(drill 0.499872)
			(layers "*.Cu" "*.Mask")
			(remove_unused_layers no)
			(net "GND")
			(clearance 0.1778)
			(thermal_gap 0.1778)
		)
		(pad "S5" thru_hole circle
			(at 5.715 -1.27 180)
			(size 0.8636 0.8636)
			(drill 0.499872)
			(layers "*.Cu" "*.Mask")
			(remove_unused_layers no)
			(net "HBA_MB_RX_N3")
			(clearance 0.1778)
			(thermal_gap 0.1778)
		)
		(pad "S6" thru_hole circle
			(at 4.445 -1.27 180)
			(size 0.8636 0.8636)
			(drill 0.499872)
			(layers "*.Cu" "*.Mask")
			(remove_unused_layers no)
			(net "HBA_MB_RX_P3")
			(clearance 0.1778)
			(thermal_gap 0.1778)
		)
		(pad "S7" thru_hole circle
			(at 3.175 -1.27 180)
			(size 0.8636 0.8636)
			(drill 0.499872)
			(layers "*.Cu" "*.Mask")
			(remove_unused_layers no)
			(net "GND")
			(clearance 0.1778)
			(thermal_gap 0.1778)
		)
		(pad "S8" thru_hole oval
			(at 2.4003 2.13995 180)
			(size 0.6096 0.8128)
			(drill 0.399796)
			(layers "*.Cu" "*.Mask")
			(remove_unused_layers no)
			(net "GND")
			(clearance 0.254)
			(thermal_gap 0.254)
		)
		(pad "S9" thru_hole oval
			(at 1.6002 2.13995 180)
			(size 0.6096 0.8128)
			(drill 0.399796)
			(layers "*.Cu" "*.Mask")
			(remove_unused_layers no)
			(net "Net_48")
			(clearance 0.254)
			(thermal_gap 0.254)
		)
		(pad "S10" thru_hole oval
			(at 0.8001 2.13995 180)
			(size 0.6096 0.8128)
			(drill 0.399796)
			(layers "*.Cu" "*.Mask")
			(remove_unused_layers no)
			(net "Net_47")
			(clearance 0.254)
			(thermal_gap 0.254)
		)
		(pad "S11" thru_hole oval
			(at 0 2.13995 180)
			(size 0.6096 0.8128)
			(drill 0.399796)
			(layers "*.Cu" "*.Mask")
			(remove_unused_layers no)
			(net "Net_43")
			(clearance 0.254)
			(thermal_gap 0.254)
		)
		(pad "S12" thru_hole oval
			(at -0.8001 2.13995 180)
			(size 0.6096 0.8128)
			(drill 0.399796)
			(layers "*.Cu" "*.Mask")
			(remove_unused_layers no)
			(net "Net_46")
			(clearance 0.254)
			(thermal_gap 0.254)
		)
		(pad "S13" thru_hole oval
			(at -1.6002 2.13995 180)
			(size 0.6096 0.8128)
			(drill 0.399796)
			(layers "*.Cu" "*.Mask")
			(remove_unused_layers no)
			(net "Net_45")
			(clearance 0.254)
			(thermal_gap 0.254)
		)
		(pad "S14" thru_hole oval
			(at -2.4003 2.13995 180)
			(size 0.6096 0.8128)
			(drill 0.399796)
			(layers "*.Cu" "*.Mask")
			(remove_unused_layers no)
			(net "GND")
			(clearance 0.254)
			(thermal_gap 0.254)
		)
	)
)
